# T6G (Grand Teton) — schematic netlist excerpt (pin names and nets, part order shuffled) for the footprints in the layout excerpt that follows; sources: Cadence DE-HDL packaged netlist, KiCad conversion of 04192023_DAF0TMB3IC0_F0TG_MB_C_brd_V02_OCP.brd

J32  SCONN288_DDR506112002KQ  IO  pkg DDR288S_1-1VXC  page 102
  VIN_BULK0  = P12V_MEM_CPU1
  RFU0  = NC
  VIN_MGMT  = P3V3_AUX
  HSCL  = I3C_SPD_DDRE_CPU1_SCL
  HSDA  = I3C_SPD_DDRE_CPU1_SDA
  VSS0  = GND
  DQ0_A  = M_E_CPU1_SA_DQ<0>
  VSS1  = GND
  DQ1_A  = M_E_CPU1_SA_DQ<1>
  VSS2  = GND
  DQS0_A_T  = M_E_CPU1_SA_DQS_DP<0>
  DQS0_A_C  = M_E_CPU1_SA_DQS_DN<0>
  VSS3  = GND
  DQ4_A  = M_E_CPU1_SA_DQ<4>
  VSS4  = GND
  DQ5_A  = M_E_CPU1_SA_DQ<5>
  VSS5  = GND
  DQ8_A  = M_E_CPU1_SA_DQ<8>
  VSS6  = GND
  DQ9_A  = M_E_CPU1_SA_DQ<9>
  VSS7  = GND
  DQS1_A_T  = M_E_CPU1_SA_DQS_DP<1>
  DQS1_A_C  = M_E_CPU1_SA_DQS_DN<1>
  VSS8  = GND
  DQ12_A  = M_E_CPU1_SA_DQ<12>
  VSS9  = GND
  DQ13_A  = M_E_CPU1_SA_DQ<13>
  VSS10  = GND
  DQ16_A  = M_E_CPU1_SA_DQ<16>
  VSS11  = GND
  DQ17_A  = M_E_CPU1_SA_DQ<17>
  VSS12  = GND
  DQS2_A_T  = M_E_CPU1_SA_DQS_DP<2>
  DQS2_A_C  = M_E_CPU1_SA_DQS_DN<2>
  VSS13  = GND
  DQ20_A  = M_E_CPU1_SA_DQ<20>
  VSS14  = GND
  DQ21_A  = M_E_CPU1_SA_DQ<21>
  VSS15  = GND
  DQ24_A  = M_E_CPU1_SA_DQ<24>
  VSS16  = GND
  DQ25_A  = M_E_CPU1_SA_DQ<25>
  VSS17  = GND
  DQS3_A_T  = M_E_CPU1_SA_DQS_DP<3>
  DQS3_A_C  = M_E_CPU1_SA_DQS_DN<3>
  VSS18  = GND
  DQ28_A  = M_E_CPU1_SA_DQ<28>
  VSS19  = GND
  DQ29_A  = M_E_CPU1_SA_DQ<29>
  VSS20  = GND
  CB0_A  = M_E_CPU1_SA_CB<0>
  VSS21  = GND
  CB1_A  = M_E_CPU1_SA_CB<1>
  VSS22  = GND
  DQS4_A_T  = M_E_CPU1_SA_DQS_DP<4>
  DQS4_A_C  = M_E_CPU1_SA_DQS_DN<4>
  VSS23  = GND
  CB4_A  = M_E_CPU1_SA_CB<4>
  VSS24  = GND
  CB5_A  = M_E_CPU1_SA_CB<5>
  VSS25  = GND
  ALERT_N  = M_E_CPU1_ALERT_N
  VSS26  = GND
  CS0_A_N  = M_E_CPU1_SA_CS_N<0>
  VSS27  = GND
  CA0_A  = M_E_CPU1_SA_CA<0>
  VSS28  = GND
  CA2_A  = M_E_CPU1_SA_CA<2>
  VSS29  = GND
  CA4_A  = M_E_CPU1_SA_CA<4>
  VSS30  = GND
  CA6_A  = M_E_CPU1_SA_CA<6>
  VSS31  = GND
  PAR_A  = M_E_CPU1_SA_PAR
  VSS32  = GND
  CA0_B  = M_E_CPU1_SB_CA<0>
  VSS33  = GND
  CA2_B  = M_E_CPU1_SB_CA<2>
  VSS34  = GND
  CA4_B  = M_E_CPU1_SB_CA<4>
  VSS35  = GND
  CA6_B  = M_E_CPU1_SB_CA<6>
  VSS36  = GND
  CS0_B_N  = M_E_CPU1_SB_CS_N<0>
  VSS37  = GND
  \lbd||rsp_a_n\  = M_E_CPU1_SA_RSP<0>
  \lbs||rsp_b_n\  = M_E_CPU1_SB_RSP<0>
  VSS38  = GND
  CB4_B  = M_E_CPU1_SB_CB<4>
  VSS39  = GND
  CB5_B  = M_E_CPU1_SB_CB<5>
  VSS40  = GND
  \dqs9_b_t||tdqs9_b_t||dbi4_b_n\  = M_E_CPU1_SB_DQS_DP<9>
  \dqs9_b_c||tdqs9_b_c\  = M_E_CPU1_SB_DQS_DN<9>
  VSS41  = GND
  CB0_B  = M_E_CPU1_SB_CB<0>
  VSS42  = GND
  CB1_B  = M_E_CPU1_SB_CB<1>
  VSS43  = GND
  DQ0_B  = M_E_CPU1_SB_DQ<0>
  VSS44  = GND
  DQ1_B  = M_E_CPU1_SB_DQ<1>
  VSS45  = GND
  DQS0_B_T  = M_E_CPU1_SB_DQS_DP<0>
  DQS0_B_C  = M_E_CPU1_SB_DQS_DN<0>
  VSS46  = GND
  DQ4_B  = M_E_CPU1_SB_DQ<4>
  VSS47  = GND
  DQ5_B  = M_E_CPU1_SB_DQ<5>
  VSS48  = GND
  DQ8_B  = M_E_CPU1_SB_DQ<8>
  VSS49  = GND
  DQ9_B  = M_E_CPU1_SB_DQ<9>
  VSS50  = GND
  DQS1_B_T  = M_E_CPU1_SB_DQS_DP<1>
  DQS1_B_C  = M_E_CPU1_SB_DQS_DN<1>
  VSS51  = GND
  DQ12_B  = M_E_CPU1_SB_DQ<12>
  VSS52  = GND
  DQ13_B  = M_E_CPU1_SB_DQ<13>
  VSS53  = GND
  DQ16_B  = M_E_CPU1_SB_DQ<16>
  VSS54  = GND
  DQ17_B  = M_E_CPU1_SB_DQ<17>
  VSS55  = GND
  DQS2_B_T  = M_E_CPU1_SB_DQS_DP<2>
  DQS2_B_C  = M_E_CPU1_SB_DQS_DN<2>
  VSS56  = GND
  DQ20_B  = M_E_CPU1_SB_DQ<20>
  VSS57  = GND
  DQ21_B  = M_E_CPU1_SB_DQ<21>
  VSS58  = GND
  DQ24_B  = M_E_CPU1_SB_DQ<24>
  VSS59  = GND
  DQ25_B  = M_E_CPU1_SB_DQ<25>
  VSS60  = GND
  DQS3_B_T  = M_E_CPU1_SB_DQS_DP<3>
  DQS3_B_C  = M_E_CPU1_SB_DQS_DN<3>
  VSS61  = GND
  DQ28_B  = M_E_CPU1_SB_DQ<28>
  VSS62  = GND
  DQ29_B  = M_E_CPU1_SB_DQ<29>
  VSS63  = GND
  RFU1  = NC
  VIN_BULK1  = P12V_MEM_CPU1
  VIN_BULK2  = P12V_MEM_CPU1
  \pwr_good||fail_n\  = PWRGD_CHE_CPU1_DIMM
  HAS  = PD_CHE_CPU1_DIMM_SAA
  RFU2  = NC
  RFU3  = NC
  VSS64  = GND
  DQ2_A  = M_E_CPU1_SA_DQ<2>
  VSS65  = GND
  DQ3_A  = M_E_CPU1_SA_DQ<3>
  VSS66  = GND
  \dqs5_a_c||tdqs5_a_c||dqs5_a_t||tdqs5_a_t\  = M_E_CPU1_SA_DQS_DN<5>
  \dqs5_a_t||tdqs5_a_t\  = M_E_CPU1_SA_DQS_DP<5>
  VSS67  = GND
  DQ6_A  = M_E_CPU1_SA_DQ<6>
  VSS68  = GND
  DQ7_A  = M_E_CPU1_SA_DQ<7>
  VSS69  = GND
  DQ10_A  = M_E_CPU1_SA_DQ<10>
  VSS70  = GND
  DQ11_A  = M_E_CPU1_SA_DQ<11>
  VSS71  = GND
  \dqs6_a_c||tdqs6_a_c||dqs6_a_t||tdqs6_a_t\  = M_E_CPU1_SA_DQS_DN<6>
  \dqs6_a_t||tdqs6_a_t\  = M_E_CPU1_SA_DQS_DP<6>
  VSS72  = GND
  DQ14_A  = M_E_CPU1_SA_DQ<14>
  VSS73  = GND
  DQ15_A  = M_E_CPU1_SA_DQ<15>
  VSS74  = GND
  DQ18_A  = M_E_CPU1_SA_DQ<18>
  VSS75  = GND
  DQ19_A  = M_E_CPU1_SA_DQ<19>
  VSS76  = GND
  \dqs7_a_c||tdqs7_a_c\  = M_E_CPU1_SA_DQS_DN<7>
  \dqs7_a_t||tdqs7_a_t\  = M_E_CPU1_SA_DQS_DP<7>
  VSS77  = GND
  DQ22_A  = M_E_CPU1_SA_DQ<22>
  VSS78  = GND
  DQ23_A  = M_E_CPU1_SA_DQ<23>
  VSS79  = GND
  DQ26_A  = M_E_CPU1_SA_DQ<26>
  VSS80  = GND
  DQ27_A  = M_E_CPU1_SA_DQ<27>
  VSS81  = GND
  \dqs8_a_c||tdqs8_a_c\  = M_E_CPU1_SA_DQS_DN<8>
  \dqs8_a_t||tdqs8_a_t\  = M_E_CPU1_SA_DQS_DP<8>
  VSS82  = GND
  DQ30_A  = M_E_CPU1_SA_DQ<30>
  VSS83  = GND
  DQ31_A  = M_E_CPU1_SA_DQ<31>
  VSS84  = GND
  CB2_A  = M_E_CPU1_SA_CB<2>
  VSS85  = GND
  CB3_A  = M_E_CPU1_SA_CB<3>
  VSS86  = GND
  \dqs9_a_c||tdqs9_a_c\  = M_E_CPU1_SA_DQS_DN<9>
  \dqs9_a_t||tdqs9_a_t\  = M_E_CPU1_SA_DQS_DP<9>
  VSS87  = GND
  CB6_A  = M_E_CPU1_SA_CB<6>
  VSS88  = GND
  CB7_A  = M_E_CPU1_SA_CB<7>
  VSS89  = GND
  RESET_N  = M_E_CPU1_RESET_N
  VSS90  = GND
  CS1_A_N  = M_E_CPU1_SA_CS_N<1>
  VSS91  = GND
  CA1_A  = M_E_CPU1_SA_CA<1>
  VSS92  = GND
  CA3_A  = M_E_CPU1_SA_CA<3>
  VSS93  = GND
  CA5_A  = M_E_CPU1_SA_CA<5>
  VSS94  = GND
  CK_T  = M_E_CPU1_CLK_DP<0>
  CK_C  = M_E_CPU1_CLK_DN<0>
  VSS95  = GND
  RFU4  = NC
  CA1_B  = M_E_CPU1_SB_CA<1>
  VSS96  = GND
  CA3_B  = M_E_CPU1_SB_CA<3>
  VSS97  = GND
  CA5_B  = M_E_CPU1_SB_CA<5>
  VSS98  = GND
  PAR_B  = M_E_CPU1_SB_PAR
  VSS99  = GND
  CS1_B_N  = M_E_CPU1_SB_CS_N<1>
  VSS100  = GND
  RFU5  = NC
  RFU6  = NC
  VSS101  = GND
  CB6_B  = M_E_CPU1_SB_CB<6>
  VSS102  = GND
  CB7_B  = M_E_CPU1_SB_CB<7>
  VSS103  = GND
  DQS4_B_C  = M_E_CPU1_SB_DQS_DN<4>
  DQS4_B_T  = M_E_CPU1_SB_DQS_DP<4>
  VSS104  = GND
  CB2_B  = M_E_CPU1_SB_CB<2>
  VSS105  = GND
  CB3_B  = M_E_CPU1_SB_CB<3>
  VSS106  = GND
  DQ2_B  = M_E_CPU1_SB_DQ<2>
  VSS107  = GND
  DQ3_B  = M_E_CPU1_SB_DQ<3>
  VSS108  = GND
  \dqs5_b_c||tdqs5_b_c\  = M_E_CPU1_SB_DQS_DN<5>
  \dqs5_b_t||tdqs5_b_t\  = M_E_CPU1_SB_DQS_DP<5>
  VSS109  = GND
  DQ6_B  = M_E_CPU1_SB_DQ<6>
  VSS110  = GND
  DQ7_B  = M_E_CPU1_SB_DQ<7>
  VSS111  = GND
  DQ10_B  = M_E_CPU1_SB_DQ<10>
  VSS112  = GND
  DQ11_B  = M_E_CPU1_SB_DQ<11>
  VSS113  = GND
  \dqs6_b_c||tdqs6_b_c\  = M_E_CPU1_SB_DQS_DN<6>
  \dqs6_b_t||tdqs6_b_t\  = M_E_CPU1_SB_DQS_DP<6>
  VSS114  = GND
  DQ14_B  = M_E_CPU1_SB_DQ<14>
  VSS115  = GND
  DQ15_B  = M_E_CPU1_SB_DQ<15>
  VSS116  = GND
  DQ18_B  = M_E_CPU1_SB_DQ<18>
  VSS117  = GND
  DQ19_B  = M_E_CPU1_SB_DQ<19>
  VSS118  = GND
  \dqs7_b_c||tdqs7_b_c\  = M_E_CPU1_SB_DQS_DN<7>
  \dqs7_b_t||tdqs7_b_t\  = M_E_CPU1_SB_DQS_DP<7>
  VSS119  = GND
  DQ22_B  = M_E_CPU1_SB_DQ<22>
  VSS120  = GND
  DQ23_B  = M_E_CPU1_SB_DQ<23>
  VSS121  = GND
  DQ26_B  = M_E_CPU1_SB_DQ<26>
  VSS122  = GND
  DQ27_B  = M_E_CPU1_SB_DQ<27>
  VSS123  = GND
  \dqs8_b_c||tdqs8_b_c\  = M_E_CPU1_SB_DQS_DN<8>
  \dqs8_b_t||tdqs8_b_t\  = M_E_CPU1_SB_DQS_DP<8>
  VSS124  = GND
  DQ30_B  = M_E_CPU1_SB_DQ<30>
  VSS125  = GND
  DQ31_B  = M_E_CPU1_SB_DQ<31>
  VSS126  = GND
  G1  = GND
  G2  = GND
  G3  = GND

(kicad_pcb
	(version 20260206)
	(generator "pcbnew")
	(generator_version "10.0")
	(general
		(thickness 1.6)
		(legacy_teardrops no)
	)
	(paper "A4")
	(title_block
		(title "04192023_DAF0TMB3IC0_F0TG_MB_C_brd_V02_OCP.brd")
		(comment 1 "Grand Teton / footprint 4612 of 8354 (J32), pads 231-276 of 291")
	)
	(layers
		(0 "F.Cu" signal "TOP")
		(4 "In1.Cu" signal "GND")
		(6 "In2.Cu" signal "IN1")
		(8 "In3.Cu" signal "GND1")
		(10 "In4.Cu" signal "IN2")
		(12 "In5.Cu" signal "GND2")
		(14 "In6.Cu" signal "IN3")
		(16 "In7.Cu" signal "GND3")
		(18 "In8.Cu" signal "VCC")
		(20 "In9.Cu" signal "VCC1")
		(22 "In10.Cu" signal "GND4")
		(24 "In11.Cu" signal "IN4")
		(26 "In12.Cu" signal "GND5")
		(28 "In13.Cu" signal "IN5")
		(30 "In14.Cu" signal "GND6")
		(32 "In15.Cu" signal "IN6")
		(34 "In16.Cu" signal "GND7")
		(2 "B.Cu" signal "BOTTOM")
		(9 "F.Adhes" user "F.Adhesive")
		(11 "B.Adhes" user "B.Adhesive")
		(13 "F.Paste" user "Package Geometry/Pastemask Top")
		(15 "B.Paste" user "Package Geometry/Pastemask Bottom")
		(5 "F.SilkS" user "Ref Des/Silkscreen Top")
		(7 "B.SilkS" user "Ref Des/Silkscreen Bottom")
		(1 "F.Mask" user "Board Geometry/Soldermask Top")
		(3 "B.Mask" user "Board Geometry/Soldermask Bottom")
		(17 "Dwgs.User" user "User.Drawings")
		(19 "Cmts.User" user "User.Comments")
		(21 "Eco1.User" user "User.Eco1")
		(23 "Eco2.User" user "User.Eco2")
		(25 "Edge.Cuts" user "Board Geometry/Outline")
		(27 "Margin" user)
		(31 "F.CrtYd" user "Package Geometry/Place Bound Top")
		(29 "B.CrtYd" user "Package Geometry/Place Bound Bottom")
		(35 "F.Fab" user "Ref Des/Assembly Top")
		(33 "B.Fab" user "Ref Des/Assembly Bottom")
	)
	(footprint ""
		(layer "F.Cu")
		(at 27.20213 -255.560322 180)
		(property "Reference" "J32"
			(at 1.80086 -81.974436 0)
			(unlocked yes)
			(layer "F.SilkS")
			(effects
				(font
					(size 0.7874 0.5842)
					(thickness 0.1524)
				)
			)
		)
		(property "Value" ""
			(at 0 0 180)
			(layer "F.Fab")
			(effects
				(font
					(size 1.27 1.27)
				)
			)
		)
		(duplicate_pad_numbers_are_jumpers no)
		(pad "231" smd rect
			(at 2.050034 14.875002 90)
			(size 0.519938 1.4986)
			(layers "F.Cu" "F.Mask" "F.Paste")
			(net "Net_2317")
		)
		(pad "232" smd rect
			(at 2.050034 15.724886 90)
			(size 0.519938 1.4986)
			(layers "F.Cu" "F.Mask" "F.Paste")
			(net "Net_2318")
		)
		(pad "233" smd rect
			(at 2.050034 16.575024 90)
			(size 0.519938 1.4986)
			(layers "F.Cu" "F.Mask" "F.Paste")
			(net "GND")
		)
		(pad "234" smd rect
			(at 2.050034 17.424908 90)
			(size 0.519938 1.4986)
			(layers "F.Cu" "F.Mask" "F.Paste")
			(net "M_E_CPU1_SB_CB<6>")
		)
		(pad "235" smd rect
			(at 2.050034 18.275046 90)
			(size 0.519938 1.4986)
			(layers "F.Cu" "F.Mask" "F.Paste")
			(net "GND")
		)
		(pad "236" smd rect
			(at 2.050034 19.12493 90)
			(size 0.519938 1.4986)
			(layers "F.Cu" "F.Mask" "F.Paste")
			(net "M_E_CPU1_SB_CB<7>")
		)
		(pad "237" smd rect
			(at 2.050034 19.975068 90)
			(size 0.519938 1.4986)
			(layers "F.Cu" "F.Mask" "F.Paste")
			(net "GND")
		)
		(pad "238" smd rect
			(at 2.050034 20.824952 90)
			(size 0.519938 1.4986)
			(layers "F.Cu" "F.Mask" "F.Paste")
			(net "M_E_CPU1_SB_DQS_DN<4>")
		)
		(pad "239" smd rect
			(at 2.050034 21.67509 90)
			(size 0.519938 1.4986)
			(layers "F.Cu" "F.Mask" "F.Paste")
			(net "M_E_CPU1_SB_DQS_DP<4>")
		)
		(pad "240" smd rect
			(at 2.050034 22.524974 90)
			(size 0.519938 1.4986)
			(layers "F.Cu" "F.Mask" "F.Paste")
			(net "GND")
		)
		(pad "241" smd rect
			(at 2.050034 23.375112 90)
			(size 0.519938 1.4986)
			(layers "F.Cu" "F.Mask" "F.Paste")
			(net "M_E_CPU1_SB_CB<2>")
		)
		(pad "242" smd rect
			(at 2.050034 24.224996 90)
			(size 0.519938 1.4986)
			(layers "F.Cu" "F.Mask" "F.Paste")
			(net "GND")
		)
		(pad "243" smd rect
			(at 2.050034 25.07488 90)
			(size 0.519938 1.4986)
			(layers "F.Cu" "F.Mask" "F.Paste")
			(net "M_E_CPU1_SB_CB<3>")
		)
		(pad "244" smd rect
			(at 2.050034 25.925018 90)
			(size 0.519938 1.4986)
			(layers "F.Cu" "F.Mask" "F.Paste")
			(net "GND")
		)
		(pad "245" smd rect
			(at 2.050034 26.774902 90)
			(size 0.519938 1.4986)
			(layers "F.Cu" "F.Mask" "F.Paste")
			(net "M_E_CPU1_SB_DQ<2>")
		)
		(pad "246" smd rect
			(at 2.050034 27.62504 90)
			(size 0.519938 1.4986)
			(layers "F.Cu" "F.Mask" "F.Paste")
			(net "GND")
		)
		(pad "247" smd rect
			(at 2.050034 28.474924 90)
			(size 0.519938 1.4986)
			(layers "F.Cu" "F.Mask" "F.Paste")
			(net "M_E_CPU1_SB_DQ<3>")
		)
		(pad "248" smd rect
			(at 2.050034 29.325062 90)
			(size 0.519938 1.4986)
			(layers "F.Cu" "F.Mask" "F.Paste")
			(net "GND")
		)
		(pad "249" smd rect
			(at 2.050034 30.174946 90)
			(size 0.519938 1.4986)
			(layers "F.Cu" "F.Mask" "F.Paste")
			(net "M_E_CPU1_SB_DQS_DN<5>")
		)
		(pad "250" smd rect
			(at 2.050034 31.025084 90)
			(size 0.519938 1.4986)
			(layers "F.Cu" "F.Mask" "F.Paste")
			(net "M_E_CPU1_SB_DQS_DP<5>")
		)
		(pad "251" smd rect
			(at 2.050034 31.874968 90)
			(size 0.519938 1.4986)
			(layers "F.Cu" "F.Mask" "F.Paste")
			(net "GND")
		)
		(pad "252" smd rect
			(at 2.050034 32.725106 90)
			(size 0.519938 1.4986)
			(layers "F.Cu" "F.Mask" "F.Paste")
			(net "M_E_CPU1_SB_DQ<6>")
		)
		(pad "253" smd rect
			(at 2.050034 33.57499 90)
			(size 0.519938 1.4986)
			(layers "F.Cu" "F.Mask" "F.Paste")
			(net "GND")
		)
		(pad "254" smd rect
			(at 2.050034 34.425128 90)
			(size 0.519938 1.4986)
			(layers "F.Cu" "F.Mask" "F.Paste")
			(net "M_E_CPU1_SB_DQ<7>")
		)
		(pad "255" smd rect
			(at 2.050034 35.275012 90)
			(size 0.519938 1.4986)
			(layers "F.Cu" "F.Mask" "F.Paste")
			(net "GND")
		)
		(pad "256" smd rect
			(at 2.050034 36.124896 90)
			(size 0.519938 1.4986)
			(layers "F.Cu" "F.Mask" "F.Paste")
			(net "M_E_CPU1_SB_DQ<10>")
		)
		(pad "257" smd rect
			(at 2.050034 36.975034 90)
			(size 0.519938 1.4986)
			(layers "F.Cu" "F.Mask" "F.Paste")
			(net "GND")
		)
		(pad "258" smd rect
			(at 2.050034 37.824918 90)
			(size 0.519938 1.4986)
			(layers "F.Cu" "F.Mask" "F.Paste")
			(net "M_E_CPU1_SB_DQ<11>")
		)
		(pad "259" smd rect
			(at 2.050034 38.675056 90)
			(size 0.519938 1.4986)
			(layers "F.Cu" "F.Mask" "F.Paste")
			(net "GND")
		)
		(pad "260" smd rect
			(at 2.050034 39.52494 90)
			(size 0.519938 1.4986)
			(layers "F.Cu" "F.Mask" "F.Paste")
			(net "M_E_CPU1_SB_DQS_DN<6>")
		)
		(pad "261" smd rect
			(at 2.050034 40.375078 90)
			(size 0.519938 1.4986)
			(layers "F.Cu" "F.Mask" "F.Paste")
			(net "M_E_CPU1_SB_DQS_DP<6>")
		)
		(pad "262" smd rect
			(at 2.050034 41.224962 90)
			(size 0.519938 1.4986)
			(layers "F.Cu" "F.Mask" "F.Paste")
			(net "GND")
		)
		(pad "263" smd rect
			(at 2.050034 42.0751 90)
			(size 0.519938 1.4986)
			(layers "F.Cu" "F.Mask" "F.Paste")
			(net "M_E_CPU1_SB_DQ<14>")
		)
		(pad "264" smd rect
			(at 2.050034 42.924984 90)
			(size 0.519938 1.4986)
			(layers "F.Cu" "F.Mask" "F.Paste")
			(net "GND")
		)
		(pad "265" smd rect
			(at 2.050034 43.775122 90)
			(size 0.519938 1.4986)
			(layers "F.Cu" "F.Mask" "F.Paste")
			(net "M_E_CPU1_SB_DQ<15>")
		)
		(pad "266" smd rect
			(at 2.050034 44.625006 90)
			(size 0.519938 1.4986)
			(layers "F.Cu" "F.Mask" "F.Paste")
			(net "GND")
		)
		(pad "267" smd rect
			(at 2.050034 45.47489 90)
			(size 0.519938 1.4986)
			(layers "F.Cu" "F.Mask" "F.Paste")
			(net "M_E_CPU1_SB_DQ<18>")
		)
		(pad "268" smd rect
			(at 2.050034 46.325028 90)
			(size 0.519938 1.4986)
			(layers "F.Cu" "F.Mask" "F.Paste")
			(net "GND")
		)
		(pad "269" smd rect
			(at 2.050034 47.174912 90)
			(size 0.519938 1.4986)
			(layers "F.Cu" "F.Mask" "F.Paste")
			(net "M_E_CPU1_SB_DQ<19>")
		)
		(pad "270" smd rect
			(at 2.050034 48.02505 90)
			(size 0.519938 1.4986)
			(layers "F.Cu" "F.Mask" "F.Paste")
			(net "GND")
		)
		(pad "271" smd rect
			(at 2.050034 48.874934 90)
			(size 0.519938 1.4986)
			(layers "F.Cu" "F.Mask" "F.Paste")
			(net "M_E_CPU1_SB_DQS_DN<7>")
		)
		(pad "272" smd rect
			(at 2.050034 49.725072 90)
			(size 0.519938 1.4986)
			(layers "F.Cu" "F.Mask" "F.Paste")
			(net "M_E_CPU1_SB_DQS_DP<7>")
		)
		(pad "273" smd rect
			(at 2.050034 50.574956 90)
			(size 0.519938 1.4986)
			(layers "F.Cu" "F.Mask" "F.Paste")
			(net "GND")
		)
		(pad "274" smd rect
			(at 2.050034 51.425094 90)
			(size 0.519938 1.4986)
			(layers "F.Cu" "F.Mask" "F.Paste")
			(net "M_E_CPU1_SB_DQ<22>")
		)
		(pad "275" smd rect
			(at 2.050034 52.274978 90)
			(size 0.519938 1.4986)
			(layers "F.Cu" "F.Mask" "F.Paste")
			(net "GND")
		)
		(pad "276" smd rect
			(at 2.050034 53.125116 90)
			(size 0.519938 1.4986)
			(layers "F.Cu" "F.Mask" "F.Paste")
			(net "M_E_CPU1_SB_DQ<23>")
		)
	)
)
